(kicad_pcb
	(version 20260206)
	(generator "pcbnew")
	(generator_version "10.0")
	(general
		(thickness 1.6)
		(legacy_teardrops no)
	)
	(paper "A4")
	(title_block
		(title "Wiwynn_Tioga_Pass_MB.brd")
		(comment 1 "Tioga Pass / footprints 1882-1886 of 4770")
	)
	(layers
		(0 "F.Cu" signal "TOP")
		(4 "In1.Cu" signal "L2GND")
		(6 "In2.Cu" signal "L3")
		(8 "In3.Cu" signal "L4GND")
		(10 "In4.Cu" signal "L5")
		(12 "In5.Cu" signal "L6GND")
		(14 "In6.Cu" signal "L7VCC")
		(16 "In7.Cu" signal "L8VCC")
		(18 "In8.Cu" signal "L9GND")
		(20 "In9.Cu" signal "L10")
		(22 "In10.Cu" signal "L11GND")
		(24 "In11.Cu" signal "L12")
		(26 "In12.Cu" signal "L13GND")
		(2 "B.Cu" signal "BOTTOM")
		(9 "F.Adhes" user "F.Adhesive")
		(11 "B.Adhes" user "B.Adhesive")
		(13 "F.Paste" user "Package Geometry/Pastemask Top")
		(15 "B.Paste" user "Package Geometry/Pastemask Bottom")
		(5 "F.SilkS" user "Ref Des/Silkscreen Top")
		(7 "B.SilkS" user "Ref Des/Silkscreen Bottom")
		(1 "F.Mask" user "Board Geometry/Soldermask Top")
		(3 "B.Mask" user "Board Geometry/Soldermask Bottom")
		(17 "Dwgs.User" user "User.Drawings")
		(19 "Cmts.User" user "User.Comments")
		(21 "Eco1.User" user "User.Eco1")
		(23 "Eco2.User" user "User.Eco2")
		(25 "Edge.Cuts" user "Board Geometry/Outline")
		(27 "Margin" user)
		(31 "F.CrtYd" user "Package Geometry/Place Bound Top")
		(29 "B.CrtYd" user "Package Geometry/Place Bound Bottom")
		(35 "F.Fab" user "Ref Des/Assembly Top")
		(33 "B.Fab" user "Ref Des/Assembly Bottom")
	)
	(footprint ""
		(layer "F.Cu")
		(at 166.977822 -9.013952 90)
		(property "Reference" "R4G8"
			(at 0 0 90)
			(layer "F.SilkS")
			(hide yes)
			(effects
				(font
					(size 1.27 1.27)
				)
			)
		)
		(property "Value" ""
			(at 0 0 90)
			(layer "F.Fab")
			(effects
				(font
					(size 1.27 1.27)
				)
			)
		)
		(duplicate_pad_numbers_are_jumpers no)
		(fp_rect
			(start 0.2794 0.9906)
			(end -0.2794 -0.1016)
			(stroke
				(width 0)
				(type default)
			)
			(fill no)
			(layer "F.CrtYd")
		)
		(fp_line
			(start 0.2794 -0.1016)
			(end -0.2794 -0.1016)
			(stroke
				(width 0.1)
				(type default)
			)
			(layer "F.Fab")
		)
		(fp_line
			(start -0.2794 -0.1016)
			(end -0.2794 0.9906)
			(stroke
				(width 0.1)
				(type default)
			)
			(layer "F.Fab")
		)
		(fp_line
			(start 0.2794 0.9906)
			(end 0.2794 -0.1016)
			(stroke
				(width 0.1)
				(type default)
			)
			(layer "F.Fab")
		)
		(fp_line
			(start -0.2794 0.9906)
			(end 0.2794 0.9906)
			(stroke
				(width 0.1)
				(type default)
			)
			(layer "F.Fab")
		)
		(pad "1" smd rect
			(at 0 0 90)
			(size 0.508 0.508)
			(layers "F.Cu" "F.Mask" "F.Paste")
			(net "PVPP_GHJ")
		)
		(pad "2" smd rect
			(at 0 0.889 90)
			(size 0.508 0.508)
			(layers "F.Cu" "F.Mask" "F.Paste")
			(net "VSENSE_PVPP_GHJ")
		)
		(zone
			(layer "F.Cu")
			(hatch none 0.5)
			(connect_pads
				(clearance 0)
			)
			(min_thickness 0.25)
			(keepout
				(tracks allowed)
				(vias not_allowed)
				(pads allowed)
				(copperpour not_allowed)
				(footprints allowed)
			)
			(placement
				(enabled no)
				(sheetname "")
			)
			(fill
				(thermal_gap 0.5)
				(thermal_bridge_width 0.5)
				(island_removal_mode 0)
			)
			(polygon
				(pts
					(xy 167.612822 -9.267952) (xy 167.231822 -9.267952) (xy 167.231822 -8.759952) (xy 167.612822 -8.759952)
				)
			)
		)
		(zone
			(layer "F.Cu")
			(hatch none 0.5)
			(connect_pads
				(clearance 0)
			)
			(min_thickness 0.25)
			(keepout
				(tracks not_allowed)
				(vias allowed)
				(pads allowed)
				(copperpour not_allowed)
				(footprints allowed)
			)
			(placement
				(enabled no)
				(sheetname "")
			)
			(fill
				(thermal_gap 0.5)
				(thermal_bridge_width 0.5)
				(island_removal_mode 0)
			)
			(polygon
				(pts
					(xy 167.612822 -9.267952) (xy 167.231822 -9.267952) (xy 167.231822 -8.759952) (xy 167.612822 -8.759952)
				)
			)
		)
	)
	(footprint ""
		(layer "F.Cu")
		(at 250.77801 -75.65009 180)
		(property "Reference" "XLU1"
			(at 19.38401 33.79724 0)
			(unlocked yes)
			(layer "F.SilkS")
			(effects
				(font
					(size 0.7874 0.5842)
					(thickness 0.1524)
				)
				(justify left)
			)
		)
		(property "Value" ""
			(at 0 0 180)
			(layer "F.Fab")
			(effects
				(font
					(size 1.27 1.27)
				)
			)
		)
		(duplicate_pad_numbers_are_jumpers no)
		(fp_line
			(start 21.77796 31.949898)
			(end 21.77796 8.899906)
			(stroke
				(width 0.1524)
				(type default)
			)
			(layer "F.SilkS")
		)
		(fp_line
			(start 21.77796 8.899906)
			(end 18.278094 5.40004)
			(stroke
				(width 0.1524)
				(type default)
			)
			(layer "F.SilkS")
		)
		(fp_line
			(start 21.77796 -7.100062)
			(end 21.77796 -30.150054)
			(stroke
				(width 0.1524)
				(type default)
			)
			(layer "F.SilkS")
		)
		(fp_line
			(start 21.77796 -30.150054)
			(end 14.777974 -30.150054)
			(stroke
				(width 0.1524)
				(type default)
			)
			(layer "F.SilkS")
		)
		(fp_line
			(start 18.278094 5.40004)
			(end 18.278094 3.899916)
			(stroke
				(width 0.1524)
				(type default)
			)
			(layer "F.SilkS")
		)
		(fp_line
			(start 18.278094 3.899916)
			(end 17.777968 3.899916)
			(stroke
				(width 0.1524)
				(type default)
			)
			(layer "F.SilkS")
		)
		(fp_line
			(start 18.278094 -2.100072)
			(end 18.278094 -3.599942)
			(stroke
				(width 0.1524)
				(type default)
			)
			(layer "F.SilkS")
		)
		(fp_line
			(start 18.278094 -3.599942)
			(end 21.77796 -7.100062)
			(stroke
				(width 0.1524)
				(type default)
			)
			(layer "F.SilkS")
		)
		(fp_line
			(start 17.777968 3.899916)
			(end 17.777968 -2.100072)
			(stroke
				(width 0.1524)
				(type default)
			)
			(layer "F.SilkS")
		)
		(fp_line
			(start 17.777968 -2.100072)
			(end 18.278094 -2.100072)
			(stroke
				(width 0.1524)
				(type default)
			)
			(layer "F.SilkS")
		)
		(fp_line
			(start 14.777974 31.949898)
			(end 21.77796 31.949898)
			(stroke
				(width 0.1524)
				(type default)
			)
			(layer "F.SilkS")
		)
		(fp_line
			(start 14.777974 29.399992)
			(end 14.777974 31.949898)
			(stroke
				(width 0.1524)
				(type default)
			)
			(layer "F.SilkS")
		)
		(fp_line
			(start 14.777974 -27.599894)
			(end -17.622012 -27.599894)
			(stroke
				(width 0.1524)
				(type default)
			)
			(layer "F.SilkS")
		)
		(fp_line
			(start 14.777974 -30.150054)
			(end 14.777974 -27.599894)
			(stroke
				(width 0.1524)
				(type default)
			)
			(layer "F.SilkS")
		)
		(fp_line
			(start -6.171946 6.690106)
			(end -12.761976 10.649966)
			(stroke
				(width 0.1524)
				(type default)
			)
			(layer "F.SilkS")
		)
		(fp_line
			(start -6.171946 -4.890008)
			(end -6.171946 6.690106)
			(stroke
				(width 0.1524)
				(type default)
			)
			(layer "F.SilkS")
		)
		(fp_line
			(start -12.761976 10.649966)
			(end -19.221958 10.649966)
			(stroke
				(width 0.1524)
				(type default)
			)
			(layer "F.SilkS")
		)
		(fp_line
			(start -12.761976 -8.850122)
			(end -6.171946 -4.890008)
			(stroke
				(width 0.1524)
				(type default)
			)
			(layer "F.SilkS")
		)
		(fp_line
			(start -17.622012 30.39999)
			(end -17.622012 29.399992)
			(stroke
				(width 0.1524)
				(type default)
			)
			(layer "F.SilkS")
		)
		(fp_line
			(start -17.622012 29.399992)
			(end 14.777974 29.399992)
			(stroke
				(width 0.1524)
				(type default)
			)
			(layer "F.SilkS")
		)
		(fp_line
			(start -17.622012 -27.599894)
			(end -17.622012 -28.599892)
			(stroke
				(width 0.1524)
				(type default)
			)
			(layer "F.SilkS")
		)
		(fp_line
			(start -17.622012 -28.599892)
			(end -18.62201 -28.599892)
			(stroke
				(width 0.1524)
				(type default)
			)
			(layer "F.SilkS")
		)
		(fp_line
			(start -18.62201 30.39999)
			(end -17.622012 30.39999)
			(stroke
				(width 0.1524)
				(type default)
			)
			(layer "F.SilkS")
		)
		(fp_line
			(start -18.62201 29.399992)
			(end -18.62201 30.39999)
			(stroke
				(width 0.1524)
				(type default)
			)
			(layer "F.SilkS")
		)
		(fp_line
			(start -18.62201 -8.850122)
			(end -12.761976 -8.850122)
			(stroke
				(width 0.1524)
				(type default)
			)
			(layer "F.SilkS")
		)
		(fp_line
			(start -18.62201 -28.599892)
			(end -18.62201 -8.850122)
			(stroke
				(width 0.1524)
				(type default)
			)
			(layer "F.SilkS")
		)
		(fp_line
			(start -19.221958 29.399992)
			(end -18.62201 29.399992)
			(stroke
				(width 0.1524)
				(type default)
			)
			(layer "F.SilkS")
		)
		(fp_line
			(start -19.221958 10.649966)
			(end -19.221958 29.399992)
			(stroke
				(width 0.1524)
				(type default)
			)
			(layer "F.SilkS")
		)
		(fp_poly
			(pts
				(xy 19.777964 -5.100066) (xy 19.777964 -22.649942) (xy 18.839434 -22.649942) (xy 18.839434 -27.410918)
				(xy 14.777974 -27.410918) (xy 14.777974 -30.150054) (xy 21.77796 -30.150054) (xy 21.77796 -7.100062)
			)
			(stroke
				(width 0)
				(type default)
			)
			(fill no)
			(layer "F.CrtYd")
		)
		(fp_poly
			(pts
				(arc
					(start 19.777964 17.616678)
					(mid 20.051978 16.900049)
					(end 19.777964 16.183356)
				)
				(xy 19.777964 6.89991) (xy 21.77796 8.899906) (xy 21.77796 31.949898) (xy 14.777974 31.949898) (xy 14.777974 29.211016)
				(xy 18.839434 29.211016) (xy 18.839434 24.449786) (xy 19.777964 24.449786)
			)
			(stroke
				(width 0)
				(type default)
			)
			(fill no)
			(layer "F.CrtYd")
		)
		(fp_line
			(start 21.77796 31.949898)
			(end 14.777974 31.949898)
			(stroke
				(width 0.1)
				(type default)
			)
			(layer "F.Fab")
		)
		(fp_line
			(start 21.77796 8.899906)
			(end 21.77796 31.949898)
			(stroke
				(width 0.1)
				(type default)
			)
			(layer "F.Fab")
		)
		(fp_line
			(start 21.77796 -7.100062)
			(end 19.777964 -5.100066)
			(stroke
				(width 0.1)
				(type default)
			)
			(layer "F.Fab")
		)
		(fp_line
			(start 21.77796 -30.150054)
			(end 21.77796 -7.100062)
			(stroke
				(width 0.1)
				(type default)
			)
			(layer "F.Fab")
		)
		(fp_line
			(start 19.777964 24.449786)
			(end 19.777964 22.078696)
			(stroke
				(width 0.1)
				(type default)
			)
			(layer "F.Fab")
		)
		(fp_line
			(start 19.777964 21.179028)
			(end 19.777964 17.616678)
			(stroke
				(width 0.1)
				(type default)
			)
			(layer "F.Fab")
		)
		(fp_line
			(start 19.777964 16.183356)
			(end 19.777964 6.89991)
			(stroke
				(width 0.1)
				(type default)
			)
			(layer "F.Fab")
		)
		(fp_line
			(start 19.777964 6.89991)
			(end 21.77796 8.899906)
			(stroke
				(width 0.1)
				(type default)
			)
			(layer "F.Fab")
		)
		(fp_line
			(start 19.777964 -5.100066)
			(end 19.777964 -22.649942)
			(stroke
				(width 0.1)
				(type default)
			)
			(layer "F.Fab")
		)
		(fp_line
			(start 19.777964 -22.649942)
			(end 18.839434 -22.649942)
			(stroke
				(width 0.1)
				(type default)
			)
			(layer "F.Fab")
		)
		(fp_line
			(start 18.839434 29.211016)
			(end 18.839434 24.449786)
			(stroke
				(width 0.1)
				(type default)
			)
			(layer "F.Fab")
		)
		(fp_line
			(start 18.839434 24.449786)
			(end 19.777964 24.449786)
			(stroke
				(width 0.1)
				(type default)
			)
			(layer "F.Fab")
		)
		(fp_line
			(start 18.839434 -22.649942)
			(end 18.839434 -27.410918)
			(stroke
				(width 0.1)
				(type default)
			)
			(layer "F.Fab")
		)
		(fp_line
			(start 18.839434 -27.410918)
			(end 14.777974 -27.410918)
			(stroke
				(width 0.1)
				(type default)
			)
			(layer "F.Fab")
		)
		(fp_line
			(start 14.777974 31.949898)
			(end 14.777974 29.211016)
			(stroke
				(width 0.1)
				(type default)
			)
			(layer "F.Fab")
		)
		(fp_line
			(start 14.777974 29.211016)
			(end 18.839434 29.211016)
			(stroke
				(width 0.1)
				(type default)
			)
			(layer "F.Fab")
		)
		(fp_line
			(start 14.777974 -27.410918)
			(end 14.777974 -30.150054)
			(stroke
				(width 0.1)
				(type default)
			)
			(layer "F.Fab")
		)
		(fp_line
			(start 14.777974 -30.150054)
			(end 21.77796 -30.150054)
			(stroke
				(width 0.1)
				(type default)
			)
			(layer "F.Fab")
		)
		(fp_arc
			(start 19.777964 22.078696)
			(mid 19.777668 21.628862)
			(end 19.777964 21.179028)
			(stroke
				(width 0.1)
				(type default)
			)
			(layer "F.Fab")
		)
		(fp_arc
			(start 19.777964 16.183356)
			(mid 20.051979 16.900015)
			(end 19.777964 17.616678)
			(stroke
				(width 0.1)
				(type default)
			)
			(layer "F.Fab")
		)
	)
	(footprint ""
		(layer "F.Cu")
		(at 421.005 -117.4877 180)
		(property "Reference" "R8B18"
			(at 0 0 180)
			(layer "F.SilkS")
			(hide yes)
			(effects
				(font
					(size 1.27 1.27)
				)
			)
		)
		(property "Value" ""
			(at 0 0 180)
			(layer "F.Fab")
			(effects
				(font
					(size 1.27 1.27)
				)
			)
		)
		(duplicate_pad_numbers_are_jumpers no)
		(fp_poly
			(pts
				(xy -0.2794 -0.1016) (xy 0.2794 -0.1016) (xy 0.2794 0.9906) (xy -0.2794 0.9906)
			)
			(stroke
				(width 0)
				(type default)
			)
			(fill no)
			(layer "F.CrtYd")
		)
		(fp_line
			(start 0.2794 0.9906)
			(end 0.2794 -0.1016)
			(stroke
				(width 0.1)
				(type default)
			)
			(layer "F.Fab")
		)
		(fp_line
			(start 0.2794 -0.1016)
			(end -0.2794 -0.1016)
			(stroke
				(width 0.1)
				(type default)
			)
			(layer "F.Fab")
		)
		(fp_line
			(start -0.2794 0.9906)
			(end 0.2794 0.9906)
			(stroke
				(width 0.1)
				(type default)
			)
			(layer "F.Fab")
		)
		(fp_line
			(start -0.2794 -0.1016)
			(end -0.2794 0.9906)
			(stroke
				(width 0.1)
				(type default)
			)
			(layer "F.Fab")
		)
		(pad "1" smd rect
			(at 0 0 180)
			(size 0.508 0.508)
			(layers "F.Cu" "F.Mask" "F.Paste")
			(net "PVPP_ABC")
		)
		(pad "2" smd rect
			(at 0 0.889 180)
			(size 0.508 0.508)
			(layers "F.Cu" "F.Mask" "F.Paste")
			(net "LED_HFI1_CPU0_N")
		)
		(zone
			(layer "F.Cu")
			(hatch none 0.5)
			(connect_pads
				(clearance 0)
			)
			(min_thickness 0.25)
			(keepout
				(tracks allowed)
				(vias not_allowed)
				(pads allowed)
				(copperpour not_allowed)
				(footprints allowed)
			)
			(placement
				(enabled no)
				(sheetname "")
			)
			(fill
				(thermal_gap 0.5)
				(thermal_bridge_width 0.5)
				(island_removal_mode 0)
			)
			(polygon
				(pts
					(xy 421.259 -117.7417) (xy 420.751 -117.7417) (xy 420.750746 -118.1227) (xy 421.259254 -118.1227)
				)
			)
		)
		(zone
			(layer "F.Cu")
			(hatch none 0.5)
			(connect_pads
				(clearance 0)
			)
			(min_thickness 0.25)
			(keepout
				(tracks not_allowed)
				(vias allowed)
				(pads allowed)
				(copperpour not_allowed)
				(footprints allowed)
			)
			(placement
				(enabled no)
				(sheetname "")
			)
			(fill
				(thermal_gap 0.5)
				(thermal_bridge_width 0.5)
				(island_removal_mode 0)
			)
			(polygon
				(pts
					(xy 421.259254 -118.1227) (xy 420.750746 -118.1227) (xy 420.751 -117.7417) (xy 421.259 -117.7417)
				)
			)
		)
	)
	(footprint ""
		(layer "F.Cu")
		(at 403.154388 -28.490926 180)
		(property "Reference" "R25W108"
			(at -0.8382 -0.67818 180)
			(unlocked yes)
			(layer "F.SilkS")
			(effects
				(font
					(size 0.4064 0.254)
					(thickness 0.1524)
				)
				(justify left)
			)
		)
		(property "Value" ""
			(at 0 0 180)
			(layer "F.Fab")
			(effects
				(font
					(size 1.27 1.27)
				)
			)
		)
		(duplicate_pad_numbers_are_jumpers no)
		(fp_poly
			(pts
				(xy -0.2794 -0.1016) (xy 0.2794 -0.1016) (xy 0.2794 0.9906) (xy -0.2794 0.9906)
			)
			(stroke
				(width 0)
				(type default)
			)
			(fill no)
			(layer "F.CrtYd")
		)
		(fp_line
			(start 0.2794 0.9906)
			(end 0.2794 -0.1016)
			(stroke
				(width 0.1)
				(type default)
			)
			(layer "F.Fab")
		)
		(fp_line
			(start 0.2794 -0.1016)
			(end -0.2794 -0.1016)
			(stroke
				(width 0.1)
				(type default)
			)
			(layer "F.Fab")
		)
		(fp_line
			(start -0.2794 0.9906)
			(end 0.2794 0.9906)
			(stroke
				(width 0.1)
				(type default)
			)
			(layer "F.Fab")
		)
		(fp_line
			(start -0.2794 -0.1016)
			(end -0.2794 0.9906)
			(stroke
				(width 0.1)
				(type default)
			)
			(layer "F.Fab")
		)
		(pad "1" smd rect
			(at 0 0 180)
			(size 0.508 0.508)
			(layers "F.Cu" "F.Mask" "F.Paste")
			(net "P3V3_STBY")
		)
		(pad "2" smd rect
			(at 0 0.889 180)
			(size 0.508 0.508)
			(layers "F.Cu" "F.Mask" "F.Paste")
			(net "RMII_BMC_OCP_TXD1_R")
		)
		(zone
			(layer "F.Cu")
			(hatch none 0.5)
			(connect_pads
				(clearance 0)
			)
			(min_thickness 0.25)
			(keepout
				(tracks not_allowed)
				(vias allowed)
				(pads allowed)
				(copperpour not_allowed)
				(footprints allowed)
			)
			(placement
				(enabled no)
				(sheetname "")
			)
			(fill
				(thermal_gap 0.5)
				(thermal_bridge_width 0.5)
				(island_removal_mode 0)
			)
			(polygon
				(pts
					(xy 403.408388 -29.125926) (xy 402.900388 -29.125926) (xy 402.900388 -28.744926) (xy 403.408388 -28.744926)
				)
			)
		)
		(zone
			(layer "F.Cu")
			(hatch none 0.5)
			(connect_pads
				(clearance 0)
			)
			(min_thickness 0.25)
			(keepout
				(tracks allowed)
				(vias not_allowed)
				(pads allowed)
				(copperpour not_allowed)
				(footprints allowed)
			)
			(placement
				(enabled no)
				(sheetname "")
			)
			(fill
				(thermal_gap 0.5)
				(thermal_bridge_width 0.5)
				(island_removal_mode 0)
			)
			(polygon
				(pts
					(xy 403.408388 -28.744926) (xy 402.900388 -28.744926) (xy 402.900388 -29.125926) (xy 403.408388 -29.125926)
				)
			)
		)
	)
	(footprint ""
		(layer "F.Cu")
		(at 404.43658 -143.561816 -90)
		(property "Reference" "C8A12"
			(at 0 0 270)
			(layer "F.SilkS")
			(hide yes)
			(effects
				(font
					(size 1.27 1.27)
				)
			)
		)
		(property "Value" ""
			(at 0 0 270)
			(layer "F.Fab")
			(effects
				(font
					(size 1.27 1.27)
				)
			)
		)
		(duplicate_pad_numbers_are_jumpers no)
		(fp_poly
			(pts
				(xy -0.7239 -0.2159) (xy 0.7239 -0.2159) (xy 0.7239 1.9939) (xy -0.7239 1.9939)
			)
			(stroke
				(width 0)
				(type default)
			)
			(fill no)
			(layer "F.CrtYd")
		)
		(fp_line
			(start -0.7239 1.9939)
			(end 0.7239 1.9939)
			(stroke
				(width 0.1)
				(type default)
			)
			(layer "F.Fab")
		)
		(fp_line
			(start 0.7239 1.9939)
			(end 0.7239 -0.2159)
			(stroke
				(width 0.1)
				(type default)
			)
			(layer "F.Fab")
		)
		(fp_line
			(start -0.7239 -0.2159)
			(end -0.7239 1.9939)
			(stroke
				(width 0.1)
				(type default)
			)
			(layer "F.Fab")
		)
		(fp_line
			(start 0.7239 -0.2159)
			(end -0.7239 -0.2159)
			(stroke
				(width 0.1)
				(type default)
			)
			(layer "F.Fab")
		)
		(pad "1" smd rect
			(at 0 0 270)
			(size 1.27 1.016)
			(layers "F.Cu" "F.Mask" "F.Paste")
			(net "P1V8_PCH_STBY")
		)
		(pad "2" smd rect
			(at 0 1.778 270)
			(size 1.27 1.016)
			(layers "F.Cu" "F.Mask" "F.Paste")
			(net "GND")
		)
		(zone
			(layer "F.Cu")
			(hatch none 0.5)
			(connect_pads
				(clearance 0)
			)
			(min_thickness 0.25)
			(keepout
				(tracks not_allowed)
				(vias allowed)
				(pads allowed)
				(copperpour not_allowed)
				(footprints allowed)
			)
			(placement
				(enabled no)
				(sheetname "")
			)
			(fill
				(thermal_gap 0.5)
				(thermal_bridge_width 0.5)
				(island_removal_mode 0)
			)
			(polygon
				(pts
					(xy 403.92858 -144.196816) (xy 403.92858 -142.926816) (xy 403.16658 -142.926816) (xy 403.16658 -144.196816)
				)
			)
		)
	)
)
